(kicad_pcb
	(version 20260206)
	(generator "pcbnew")
	(generator_version "10.0")
	(general
		(thickness 1.6)
		(legacy_teardrops no)
	)
	(paper "A4")
	(title_block
		(title "panther-plus-userver — 13130-1b_20150205.brd")
		(comment 1 "Honey Badger (Wiwynn) / footprints 722-729 of 1509")
	)
	(layers
		(0 "F.Cu" signal "TOP")
		(4 "In1.Cu" signal "L2")
		(6 "In2.Cu" signal "L3")
		(8 "In3.Cu" signal "L4")
		(10 "In4.Cu" signal "L5")
		(12 "In5.Cu" signal "L6")
		(14 "In6.Cu" signal "L7")
		(16 "In7.Cu" signal "L8")
		(18 "In8.Cu" signal "L9")
		(20 "In9.Cu" signal "L10")
		(22 "In10.Cu" signal "L11")
		(2 "B.Cu" signal "BOTTOM")
		(9 "F.Adhes" user "F.Adhesive")
		(11 "B.Adhes" user "B.Adhesive")
		(13 "F.Paste" user "Package Geometry/Pastemask Top")
		(15 "B.Paste" user "Package Geometry/Pastemask Bottom")
		(5 "F.SilkS" user "Ref Des/Silkscreen Top")
		(7 "B.SilkS" user "Ref Des/Silkscreen Bottom")
		(1 "F.Mask" user "Board Geometry/Soldermask Top")
		(3 "B.Mask" user "Board Geometry/Soldermask Bottom")
		(17 "Dwgs.User" user "User.Drawings")
		(19 "Cmts.User" user "User.Comments")
		(21 "Eco1.User" user "User.Eco1")
		(23 "Eco2.User" user "User.Eco2")
		(25 "Edge.Cuts" user "Board Geometry/Outline")
		(27 "Margin" user)
		(31 "F.CrtYd" user "Package Geometry/Place Bound Top")
		(29 "B.CrtYd" user "Package Geometry/Place Bound Bottom")
		(35 "F.Fab" user "Ref Des/Assembly Top")
		(33 "B.Fab" user "Ref Des/Assembly Bottom")
	)
	(footprint ""
		(layer "F.Cu")
		(at 184.15 -53.848 180)
		(property "Reference" "R203"
			(at 0 0 180)
			(layer "F.SilkS")
			(hide yes)
			(effects
				(font
					(size 1.27 1.27)
				)
			)
		)
		(property "Value" "100R2F-L1-GP-U"
			(at 0.064008 -3.993896 180)
			(unlocked yes)
			(layer "F.Fab")
			(hide yes)
			(effects
				(font
					(size 1.016 1.016)
					(thickness 0.1524)
				)
			)
		)
		(property "Device Type" "R402H14"
			(at 0.064008 -5.517896 180)
			(unlocked yes)
			(layer "F.Fab")
			(hide yes)
			(effects
				(font
					(size 1.016 1.016)
					(thickness 0.1524)
				)
			)
		)
		(duplicate_pad_numbers_are_jumpers no)
		(fp_rect
			(start -0.381 0.8382)
			(end 0.381 -0.8382)
			(stroke
				(width 0)
				(type default)
			)
			(fill no)
			(layer "F.CrtYd")
		)
		(fp_rect
			(start -0.381 0.8382)
			(end 0.381 -0.8382)
			(stroke
				(width 0)
				(type default)
			)
			(fill no)
			(layer "F.Fab")
		)
		(pad "1" smd custom
			(at 0 -0.4318 180)
			(size 0.127 0.127)
			(layers "F.Cu" "F.Mask" "F.Paste")
			(net "PV_VDDR_VREF_A_FB")
			(options
				(clearance outline)
				(anchor circle)
			)
			(primitives
				(gr_poly
					(pts
						(arc
							(start -0.2032 -0.2794)
							(mid -0.239121 -0.264521)
							(end -0.254 -0.2286)
						)
						(arc
							(start -0.254 0.2286)
							(mid -0.239121 0.264521)
							(end -0.2032 0.2794)
						)
						(arc
							(start 0.2032 0.2794)
							(mid 0.239121 0.264521)
							(end 0.254 0.2286)
						)
						(arc
							(start 0.254 -0.2286)
							(mid 0.239121 -0.264521)
							(end 0.2032 -0.2794)
						)
					)
					(width 0)
					(fill yes)
				)
			)
		)
		(pad "2" smd custom
			(at 0 0.4318 180)
			(size 0.127 0.127)
			(layers "F.Cu" "F.Mask" "F.Paste")
			(net "GND")
			(options
				(clearance outline)
				(anchor circle)
			)
			(primitives
				(gr_poly
					(pts
						(arc
							(start -0.2032 -0.2794)
							(mid -0.239121 -0.264521)
							(end -0.254 -0.2286)
						)
						(arc
							(start -0.254 0.2286)
							(mid -0.239121 0.264521)
							(end -0.2032 0.2794)
						)
						(arc
							(start 0.2032 0.2794)
							(mid 0.239121 0.264521)
							(end 0.254 0.2286)
						)
						(arc
							(start 0.254 -0.2286)
							(mid 0.239121 -0.264521)
							(end 0.2032 -0.2794)
						)
					)
					(width 0)
					(fill yes)
				)
			)
		)
	)
	(footprint ""
		(layer "F.Cu")
		(at 50.038 -41.021 90)
		(property "Reference" "Q4"
			(at 0 0 90)
			(layer "F.SilkS")
			(hide yes)
			(effects
				(font
					(size 1.27 1.27)
				)
			)
		)
		(property "Value" "AO4406AL-GP"
			(at -3.707384 -1.5367 90)
			(unlocked yes)
			(layer "F.Fab")
			(hide yes)
			(effects
				(font
					(size 1.016 1.016)
					(thickness 0.1524)
				)
			)
		)
		(property "Device Type" "SOIC8H69"
			(at -3.707384 -3.0607 90)
			(unlocked yes)
			(layer "F.Fab")
			(hide yes)
			(effects
				(font
					(size 1.016 1.016)
					(thickness 0.1524)
				)
			)
		)
		(duplicate_pad_numbers_are_jumpers no)
		(fp_line
			(start 2.1463 -1.4351)
			(end -2.6797 -1.4351)
			(stroke
				(width 0.1524)
				(type default)
			)
			(layer "F.SilkS")
		)
		(fp_line
			(start -2.6797 -1.4351)
			(end -2.6797 1.4351)
			(stroke
				(width 0.1524)
				(type default)
			)
			(layer "F.SilkS")
		)
		(fp_line
			(start -2.6797 -0.508)
			(end -2.6797 0.508)
			(stroke
				(width 0.1524)
				(type default)
			)
			(layer "F.SilkS")
		)
		(fp_line
			(start -2.1717 0)
			(end -2.6797 -0.508)
			(stroke
				(width 0.1524)
				(type default)
			)
			(layer "F.SilkS")
		)
		(fp_line
			(start -2.6797 0.508)
			(end -2.1717 0)
			(stroke
				(width 0.1524)
				(type default)
			)
			(layer "F.SilkS")
		)
		(fp_line
			(start -2.502154 1.4224)
			(end -2.502154 3.1115)
			(stroke
				(width 0.508)
				(type default)
			)
			(layer "F.SilkS")
		)
		(fp_line
			(start 2.1463 1.4351)
			(end 2.1463 -1.4351)
			(stroke
				(width 0.1524)
				(type default)
			)
			(layer "F.SilkS")
		)
		(fp_line
			(start -2.6797 1.4351)
			(end 2.1463 1.4351)
			(stroke
				(width 0.1524)
				(type default)
			)
			(layer "F.SilkS")
		)
		(fp_poly
			(pts
				(xy -2.2225 -1.4351) (xy -2.2225 1.4351) (xy 2.1463 1.4351) (xy 2.1463 -1.4351)
			)
			(stroke
				(width 0)
				(type default)
			)
			(fill yes)
			(layer "F.SilkS")
		)
		(fp_rect
			(start -2.7559 3.3655)
			(end 2.7559 -3.3655)
			(stroke
				(width 0)
				(type default)
			)
			(fill no)
			(layer "F.CrtYd")
		)
		(fp_rect
			(start -2.7559 3.3655)
			(end 2.7559 -3.3655)
			(stroke
				(width 0)
				(type default)
			)
			(fill no)
			(layer "F.Fab")
		)
		(pad "1" smd rect
			(at -1.905 2.4765 90)
			(size 0.635 1.524)
			(layers "F.Cu" "F.Mask" "F.Paste")
			(net "P3V3")
		)
		(pad "2" smd rect
			(at -0.635 2.4765 90)
			(size 0.635 1.524)
			(layers "F.Cu" "F.Mask" "F.Paste")
			(net "P3V3")
		)
		(pad "3" smd rect
			(at 0.635 2.4765 90)
			(size 0.635 1.524)
			(layers "F.Cu" "F.Mask" "F.Paste")
			(net "P3V3")
		)
		(pad "4" smd rect
			(at 1.905 2.4765 90)
			(size 0.635 1.524)
			(layers "F.Cu" "F.Mask" "F.Paste")
			(net "SW_P3V3_EN_LV_D")
		)
		(pad "5" smd rect
			(at 1.905 -2.4765 90)
			(size 0.635 1.524)
			(layers "F.Cu" "F.Mask" "F.Paste")
			(net "P3V3_STBY")
		)
		(pad "6" smd rect
			(at 0.635 -2.4765 90)
			(size 0.635 1.524)
			(layers "F.Cu" "F.Mask" "F.Paste")
			(net "P3V3_STBY")
		)
		(pad "7" smd rect
			(at -0.635 -2.4765 90)
			(size 0.635 1.524)
			(layers "F.Cu" "F.Mask" "F.Paste")
			(net "P3V3_STBY")
		)
		(pad "8" smd rect
			(at -1.905 -2.4765 90)
			(size 0.635 1.524)
			(layers "F.Cu" "F.Mask" "F.Paste")
			(net "P3V3_STBY")
		)
	)
	(footprint ""
		(layer "F.Cu")
		(at 72.263 -42.926)
		(property "Reference" "R55"
			(at 0 0 0)
			(layer "F.SilkS")
			(hide yes)
			(effects
				(font
					(size 1.27 1.27)
				)
			)
		)
		(property "Value" "0R2J-2-GP"
			(at 1.7907 -1.1176 0)
			(unlocked yes)
			(layer "F.Fab")
			(hide yes)
			(effects
				(font
					(size 1.016 1.016)
					(thickness 0.1524)
				)
			)
		)
		(property "Device Type" "R402H16"
			(at 1.7907 -2.6416 0)
			(unlocked yes)
			(layer "F.Fab")
			(hide yes)
			(effects
				(font
					(size 1.016 1.016)
					(thickness 0.1524)
				)
			)
		)
		(duplicate_pad_numbers_are_jumpers no)
		(fp_rect
			(start -0.381 0.8382)
			(end 0.381 -0.8382)
			(stroke
				(width 0)
				(type default)
			)
			(fill no)
			(layer "F.CrtYd")
		)
		(fp_rect
			(start -0.381 0.8382)
			(end 0.381 -0.8382)
			(stroke
				(width 0)
				(type default)
			)
			(fill no)
			(layer "F.Fab")
		)
		(pad "1" smd custom
			(at 0 -0.4318)
			(size 0.127 0.127)
			(layers "F.Cu" "F.Mask" "F.Paste")
			(net "SMBUS_SW_R_EN")
			(options
				(clearance outline)
				(anchor circle)
			)
			(primitives
				(gr_poly
					(pts
						(arc
							(start -0.2032 -0.2794)
							(mid -0.239121 -0.264521)
							(end -0.254 -0.2286)
						)
						(arc
							(start -0.254 0.2286)
							(mid -0.239121 0.264521)
							(end -0.2032 0.2794)
						)
						(arc
							(start 0.2032 0.2794)
							(mid 0.239121 0.264521)
							(end 0.254 0.2286)
						)
						(arc
							(start 0.254 -0.2286)
							(mid 0.239121 -0.264521)
							(end 0.2032 -0.2794)
						)
					)
					(width 0)
					(fill yes)
				)
			)
		)
		(pad "2" smd custom
			(at 0 0.4318)
			(size 0.127 0.127)
			(layers "F.Cu" "F.Mask" "F.Paste")
			(net "SMBUS_SW_EN")
			(options
				(clearance outline)
				(anchor circle)
			)
			(primitives
				(gr_poly
					(pts
						(arc
							(start -0.2032 -0.2794)
							(mid -0.239121 -0.264521)
							(end -0.254 -0.2286)
						)
						(arc
							(start -0.254 0.2286)
							(mid -0.239121 0.264521)
							(end -0.2032 0.2794)
						)
						(arc
							(start 0.2032 0.2794)
							(mid 0.239121 0.264521)
							(end 0.254 0.2286)
						)
						(arc
							(start 0.254 -0.2286)
							(mid 0.239121 -0.264521)
							(end 0.2032 -0.2794)
						)
					)
					(width 0)
					(fill yes)
				)
			)
		)
	)
	(footprint ""
		(layer "F.Cu")
		(at 128.27 -39.37 -90)
		(property "Reference" "C13"
			(at 0 0 270)
			(layer "F.SilkS")
			(hide yes)
			(effects
				(font
					(size 1.27 1.27)
				)
			)
		)
		(property "Value" "SCD1U10V2KX-5GP"
			(at 1.1811 -2.7051 270)
			(unlocked yes)
			(layer "F.Fab")
			(hide yes)
			(effects
				(font
					(size 1.016 1.016)
					(thickness 0.1524)
				)
			)
		)
		(property "Device Type" "C402H22"
			(at 1.1811 -4.2291 270)
			(unlocked yes)
			(layer "F.Fab")
			(hide yes)
			(effects
				(font
					(size 1.016 1.016)
					(thickness 0.1524)
				)
			)
		)
		(duplicate_pad_numbers_are_jumpers no)
		(fp_rect
			(start -0.381 0.7366)
			(end 0.381 -0.7366)
			(stroke
				(width 0)
				(type default)
			)
			(fill no)
			(layer "F.CrtYd")
		)
		(fp_rect
			(start -0.381 0.7366)
			(end 0.381 -0.7366)
			(stroke
				(width 0)
				(type default)
			)
			(fill no)
			(layer "F.Fab")
		)
		(pad "1" smd custom
			(at 0 -0.4572 270)
			(size 0.1143 0.1143)
			(layers "F.Cu" "F.Mask" "F.Paste")
			(net "P1V2_FPGA_D")
			(options
				(clearance outline)
				(anchor circle)
			)
			(primitives
				(gr_poly
					(pts
						(arc
							(start -0.254 -0.1778)
							(mid -0.239121 -0.213721)
							(end -0.2032 -0.2286)
						)
						(arc
							(start 0.2032 -0.2286)
							(mid 0.239121 -0.213721)
							(end 0.254 -0.1778)
						)
						(arc
							(start 0.254 0.1778)
							(mid 0.239121 0.213721)
							(end 0.2032 0.2286)
						)
						(arc
							(start -0.2032 0.2286)
							(mid -0.239121 0.213721)
							(end -0.254 0.1778)
						)
					)
					(width 0)
					(fill yes)
				)
			)
		)
		(pad "2" smd custom
			(at 0 0.4572 270)
			(size 0.1143 0.1143)
			(layers "F.Cu" "F.Mask" "F.Paste")
			(net "GND")
			(options
				(clearance outline)
				(anchor circle)
			)
			(primitives
				(gr_poly
					(pts
						(arc
							(start -0.254 -0.1778)
							(mid -0.239121 -0.213721)
							(end -0.2032 -0.2286)
						)
						(arc
							(start 0.2032 -0.2286)
							(mid 0.239121 -0.213721)
							(end 0.254 -0.1778)
						)
						(arc
							(start 0.254 0.1778)
							(mid 0.239121 0.213721)
							(end 0.2032 0.2286)
						)
						(arc
							(start -0.2032 0.2286)
							(mid -0.239121 0.213721)
							(end -0.254 0.1778)
						)
					)
					(width 0)
					(fill yes)
				)
			)
		)
	)
	(footprint ""
		(layer "F.Cu")
		(at 96.393 -68.58 180)
		(property "Reference" "TP2"
			(at 0 0 180)
			(layer "F.SilkS")
			(hide yes)
			(effects
				(font
					(size 1.27 1.27)
				)
			)
		)
		(property "Value" "TPAD28-1-GP-U"
			(at 0.0508 -1.9304 180)
			(unlocked yes)
			(layer "F.Fab")
			(hide yes)
			(effects
				(font
					(size 1.016 1.016)
					(thickness 0.1524)
				)
			)
		)
		(property "Device Type" "TPAD28-1-U"
			(at 0.0508 -3.4544 180)
			(unlocked yes)
			(layer "F.Fab")
			(hide yes)
			(effects
				(font
					(size 1.016 1.016)
					(thickness 0.1524)
				)
			)
		)
		(duplicate_pad_numbers_are_jumpers no)
		(fp_poly
			(pts
				(arc
					(start -0.3556 0)
					(mid 0.3556 0)
					(end -0.3556 0)
				)
			)
			(stroke
				(width 0)
				(type default)
			)
			(fill no)
			(layer "F.CrtYd")
		)
		(fp_poly
			(pts
				(arc
					(start -0.9525 0)
					(mid 0.9525 0)
					(end -0.9525 0)
				)
			)
			(stroke
				(width 0)
				(type default)
			)
			(fill no)
			(layer "F.Fab")
		)
		(pad "1" smd circle
			(at 0 0 180)
			(size 0.7112 0.7112)
			(layers "F.Cu" "F.Mask" "F.Paste")
			(net "TP_VDDB")
		)
	)
	(footprint ""
		(layer "F.Cu")
		(at 182.372 -36.068 180)
		(property "Reference" "PR135"
			(at 0 0 180)
			(layer "F.SilkS")
			(hide yes)
			(effects
				(font
					(size 1.27 1.27)
				)
			)
		)
		(property "Value" "5K11R2F-L1-GP"
			(at 1.7907 -1.1176 180)
			(unlocked yes)
			(layer "F.Fab")
			(hide yes)
			(effects
				(font
					(size 1.016 1.016)
					(thickness 0.1524)
				)
			)
		)
		(property "Device Type" "R402H16"
			(at 1.7907 -2.6416 180)
			(unlocked yes)
			(layer "F.Fab")
			(hide yes)
			(effects
				(font
					(size 1.016 1.016)
					(thickness 0.1524)
				)
			)
		)
		(duplicate_pad_numbers_are_jumpers no)
		(fp_rect
			(start -0.381 0.8382)
			(end 0.381 -0.8382)
			(stroke
				(width 0)
				(type default)
			)
			(fill no)
			(layer "F.CrtYd")
		)
		(fp_rect
			(start -0.381 0.8382)
			(end 0.381 -0.8382)
			(stroke
				(width 0)
				(type default)
			)
			(fill no)
			(layer "F.Fab")
		)
		(pad "1" smd custom
			(at 0 -0.4318 180)
			(size 0.127 0.127)
			(layers "F.Cu" "F.Mask" "F.Paste")
			(net "P3V3_STBY")
			(options
				(clearance outline)
				(anchor circle)
			)
			(primitives
				(gr_poly
					(pts
						(arc
							(start -0.2032 -0.2794)
							(mid -0.239121 -0.264521)
							(end -0.254 -0.2286)
						)
						(arc
							(start -0.254 0.2286)
							(mid -0.239121 0.264521)
							(end -0.2032 0.2794)
						)
						(arc
							(start 0.2032 0.2794)
							(mid 0.239121 0.264521)
							(end 0.254 0.2286)
						)
						(arc
							(start 0.254 -0.2286)
							(mid 0.239121 -0.264521)
							(end 0.2032 -0.2794)
						)
					)
					(width 0)
					(fill yes)
				)
			)
		)
		(pad "2" smd custom
			(at 0 0.4318 180)
			(size 0.127 0.127)
			(layers "F.Cu" "F.Mask" "F.Paste")
			(net "VR_PWREN_PVDDR_A")
			(options
				(clearance outline)
				(anchor circle)
			)
			(primitives
				(gr_poly
					(pts
						(arc
							(start -0.2032 -0.2794)
							(mid -0.239121 -0.264521)
							(end -0.254 -0.2286)
						)
						(arc
							(start -0.254 0.2286)
							(mid -0.239121 0.264521)
							(end -0.2032 0.2794)
						)
						(arc
							(start 0.2032 0.2794)
							(mid 0.239121 0.264521)
							(end 0.254 0.2286)
						)
						(arc
							(start 0.254 -0.2286)
							(mid 0.239121 -0.264521)
							(end 0.2032 -0.2794)
						)
					)
					(width 0)
					(fill yes)
				)
			)
		)
	)
	(footprint ""
		(layer "F.Cu")
		(at 67.6402 -42.2402 90)
		(property "Reference" "R39"
			(at 0 0 90)
			(layer "F.SilkS")
			(hide yes)
			(effects
				(font
					(size 1.27 1.27)
				)
			)
		)
		(property "Value" "0R2J-2-GP"
			(at 0.064008 -3.993896 90)
			(unlocked yes)
			(layer "F.Fab")
			(hide yes)
			(effects
				(font
					(size 1.016 1.016)
					(thickness 0.1524)
				)
			)
		)
		(property "Device Type" "R402H16"
			(at 0.064008 -5.517896 90)
			(unlocked yes)
			(layer "F.Fab")
			(hide yes)
			(effects
				(font
					(size 1.016 1.016)
					(thickness 0.1524)
				)
			)
		)
		(duplicate_pad_numbers_are_jumpers no)
		(fp_rect
			(start -0.381 0.8382)
			(end 0.381 -0.8382)
			(stroke
				(width 0)
				(type default)
			)
			(fill no)
			(layer "F.CrtYd")
		)
		(fp_rect
			(start -0.381 0.8382)
			(end 0.381 -0.8382)
			(stroke
				(width 0)
				(type default)
			)
			(fill no)
			(layer "F.Fab")
		)
		(pad "1" smd custom
			(at 0 -0.4318 90)
			(size 0.127 0.127)
			(layers "F.Cu" "F.Mask" "F.Paste")
			(net "SMBUS_HOST_R_CLK")
			(options
				(clearance outline)
				(anchor circle)
			)
			(primitives
				(gr_poly
					(pts
						(arc
							(start -0.2032 -0.2794)
							(mid -0.239121 -0.264521)
							(end -0.254 -0.2286)
						)
						(arc
							(start -0.254 0.2286)
							(mid -0.239121 0.264521)
							(end -0.2032 0.2794)
						)
						(arc
							(start 0.2032 0.2794)
							(mid 0.239121 0.264521)
							(end 0.254 0.2286)
						)
						(arc
							(start 0.254 -0.2286)
							(mid 0.239121 -0.264521)
							(end 0.2032 -0.2794)
						)
					)
					(width 0)
					(fill yes)
				)
			)
		)
		(pad "2" smd custom
			(at 0 0.4318 90)
			(size 0.127 0.127)
			(layers "F.Cu" "F.Mask" "F.Paste")
			(net "SMBUS_HOST_CLK")
			(options
				(clearance outline)
				(anchor circle)
			)
			(primitives
				(gr_poly
					(pts
						(arc
							(start -0.2032 -0.2794)
							(mid -0.239121 -0.264521)
							(end -0.254 -0.2286)
						)
						(arc
							(start -0.254 0.2286)
							(mid -0.239121 0.264521)
							(end -0.2032 0.2794)
						)
						(arc
							(start 0.2032 0.2794)
							(mid 0.239121 0.264521)
							(end 0.254 0.2286)
						)
						(arc
							(start 0.254 -0.2286)
							(mid 0.239121 -0.264521)
							(end 0.2032 -0.2794)
						)
					)
					(width 0)
					(fill yes)
				)
			)
		)
	)
	(footprint ""
		(layer "F.Cu")
		(at 9.525 -40.132 90)
		(property "Reference" "PC181"
			(at 0 0 90)
			(layer "F.SilkS")
			(hide yes)
			(effects
				(font
					(size 1.27 1.27)
				)
			)
		)
		(property "Value" "SCD1U25V2KX-2-GP"
			(at 1.8923 -1.2065 90)
			(unlocked yes)
			(layer "F.Fab")
			(hide yes)
			(effects
				(font
					(size 1.016 1.016)
					(thickness 0.1524)
				)
			)
		)
		(property "Device Type" "C402H22"
			(at 1.8923 -2.7305 90)
			(unlocked yes)
			(layer "F.Fab")
			(hide yes)
			(effects
				(font
					(size 1.016 1.016)
					(thickness 0.1524)
				)
			)
		)
		(duplicate_pad_numbers_are_jumpers no)
		(fp_rect
			(start -0.381 0.7366)
			(end 0.381 -0.7366)
			(stroke
				(width 0)
				(type default)
			)
			(fill no)
			(layer "F.CrtYd")
		)
		(fp_rect
			(start -0.381 0.7366)
			(end 0.381 -0.7366)
			(stroke
				(width 0)
				(type default)
			)
			(fill no)
			(layer "F.Fab")
		)
		(pad "1" smd custom
			(at 0 -0.4572 90)
			(size 0.1143 0.1143)
			(layers "F.Cu" "F.Mask" "F.Paste")
			(net "P3V3_STBY_VIN")
			(options
				(clearance outline)
				(anchor circle)
			)
			(primitives
				(gr_poly
					(pts
						(arc
							(start -0.254 -0.1778)
							(mid -0.239121 -0.213721)
							(end -0.2032 -0.2286)
						)
						(arc
							(start 0.2032 -0.2286)
							(mid 0.239121 -0.213721)
							(end 0.254 -0.1778)
						)
						(arc
							(start 0.254 0.1778)
							(mid 0.239121 0.213721)
							(end 0.2032 0.2286)
						)
						(arc
							(start -0.2032 0.2286)
							(mid -0.239121 0.213721)
							(end -0.254 0.1778)
						)
					)
					(width 0)
					(fill yes)
				)
			)
		)
		(pad "2" smd custom
			(at 0 0.4572 90)
			(size 0.1143 0.1143)
			(layers "F.Cu" "F.Mask" "F.Paste")
			(net "GND")
			(options
				(clearance outline)
				(anchor circle)
			)
			(primitives
				(gr_poly
					(pts
						(arc
							(start -0.254 -0.1778)
							(mid -0.239121 -0.213721)
							(end -0.2032 -0.2286)
						)
						(arc
							(start 0.2032 -0.2286)
							(mid 0.239121 -0.213721)
							(end 0.254 -0.1778)
						)
						(arc
							(start 0.254 0.1778)
							(mid 0.239121 0.213721)
							(end 0.2032 0.2286)
						)
						(arc
							(start -0.2032 0.2286)
							(mid -0.239121 0.213721)
							(end -0.254 0.1778)
						)
					)
					(width 0)
					(fill yes)
				)
			)
		)
	)
)
